# SCM (Grand Teton) — schematic netlist excerpt (pin names and nets, part order shuffled) for the footprints in the layout excerpt that follows; sources: Cadence DE-HDL packaged netlist, KiCad conversion of 12092022_DA0F0TMDCD0_F0T_Management_Board_D_brd_V3_OCP.brd

R89  Q_RES  150 1% CHIP  pkg 0402LF  page 23 : A = V_DACR_IO ; B = GND
R454  Q_RES  0 5% CHIP  pkg 0402LF  page 35 : A = SMB_BMC_ALERT4_N ; B = SMB_BMC_ALERT4_R1_N

(kicad_pcb
	(version 20260206)
	(generator "pcbnew")
	(generator_version "10.0")
	(general
		(thickness 1.6)
		(legacy_teardrops no)
	)
	(paper "A4")
	(title_block
		(title "12092022_DA0F0TMDCD0_F0T_Management_Board_D_brd_V3_OCP.brd")
		(comment 1 "Grand Teton / footprints 438-439 of 1440")
	)
	(layers
		(0 "F.Cu" signal "TOP")
		(4 "In1.Cu" signal "GND")
		(6 "In2.Cu" signal "IN1")
		(8 "In3.Cu" signal "GND1")
		(10 "In4.Cu" signal "IN2")
		(12 "In5.Cu" signal "VCC")
		(14 "In6.Cu" signal "VCC1")
		(16 "In7.Cu" signal "IN3")
		(18 "In8.Cu" signal "GND2")
		(20 "In9.Cu" signal "IN4")
		(22 "In10.Cu" signal "GND3")
		(2 "B.Cu" signal "BOTTOM")
		(9 "F.Adhes" user "F.Adhesive")
		(11 "B.Adhes" user "B.Adhesive")
		(13 "F.Paste" user "Package Geometry/Pastemask Top")
		(15 "B.Paste" user "Package Geometry/Pastemask Bottom")
		(5 "F.SilkS" user "Ref Des/Silkscreen Top")
		(7 "B.SilkS" user "Ref Des/Silkscreen Bottom")
		(1 "F.Mask" user "Board Geometry/Soldermask Top")
		(3 "B.Mask" user "Board Geometry/Soldermask Bottom")
		(17 "Dwgs.User" user "User.Drawings")
		(19 "Cmts.User" user "User.Comments")
		(21 "Eco1.User" user "User.Eco1")
		(23 "Eco2.User" user "User.Eco2")
		(25 "Edge.Cuts" user "Board Geometry/Outline")
		(27 "Margin" user)
		(31 "F.CrtYd" user "Package Geometry/Place Bound Top")
		(29 "B.CrtYd" user "Package Geometry/Place Bound Bottom")
		(35 "F.Fab" user "Ref Des/Assembly Top")
		(33 "B.Fab" user "Ref Des/Assembly Bottom")
	)
	(footprint ""
		(layer "F.Cu")
		(at 31.75 -33.274)
		(property "Reference" "R89"
			(at 0 0 0)
			(layer "F.SilkS")
			(hide yes)
			(effects
				(font
					(size 1.27 1.27)
				)
			)
		)
		(property "Value" ""
			(at 0 0 0)
			(layer "F.Fab")
			(effects
				(font
					(size 1.27 1.27)
				)
			)
		)
		(duplicate_pad_numbers_are_jumpers no)
		(fp_line
			(start -0.7874 -0.4064)
			(end 0.7874 -0.4064)
			(stroke
				(width 0.1524)
				(type default)
			)
			(layer "F.SilkS")
		)
		(fp_line
			(start -0.7874 0.4064)
			(end -0.7874 -0.4064)
			(stroke
				(width 0.1524)
				(type default)
			)
			(layer "F.SilkS")
		)
		(fp_line
			(start 0.7874 -0.4064)
			(end 0.7874 0.4064)
			(stroke
				(width 0.1524)
				(type default)
			)
			(layer "F.SilkS")
		)
		(fp_line
			(start 0.7874 0.4064)
			(end -0.7874 0.4064)
			(stroke
				(width 0.1524)
				(type default)
			)
			(layer "F.SilkS")
		)
		(fp_line
			(start -0.67945 -0.305054)
			(end -0.12065 -0.305054)
			(stroke
				(width 0.1)
				(type default)
			)
			(layer "F.Fab")
		)
		(fp_line
			(start -0.67945 0.3048)
			(end -0.67945 -0.305054)
			(stroke
				(width 0.1)
				(type default)
			)
			(layer "F.Fab")
		)
		(fp_line
			(start -0.12065 -0.305054)
			(end -0.12065 -0.2794)
			(stroke
				(width 0.1)
				(type default)
			)
			(layer "F.Fab")
		)
		(fp_line
			(start -0.12065 -0.2794)
			(end 0.12065 -0.2794)
			(stroke
				(width 0.1)
				(type default)
			)
			(layer "F.Fab")
		)
		(fp_line
			(start -0.12065 0.2794)
			(end -0.12065 0.3048)
			(stroke
				(width 0.1)
				(type default)
			)
			(layer "F.Fab")
		)
		(fp_line
			(start -0.12065 0.3048)
			(end -0.67945 0.3048)
			(stroke
				(width 0.1)
				(type default)
			)
			(layer "F.Fab")
		)
		(fp_line
			(start 0.120396 0.2794)
			(end -0.12065 0.2794)
			(stroke
				(width 0.1)
				(type default)
			)
			(layer "F.Fab")
		)
		(fp_line
			(start 0.120396 0.3048)
			(end 0.120396 0.2794)
			(stroke
				(width 0.1)
				(type default)
			)
			(layer "F.Fab")
		)
		(fp_line
			(start 0.12065 -0.3048)
			(end 0.67945 -0.3048)
			(stroke
				(width 0.1)
				(type default)
			)
			(layer "F.Fab")
		)
		(fp_line
			(start 0.12065 -0.2794)
			(end 0.12065 -0.3048)
			(stroke
				(width 0.1)
				(type default)
			)
			(layer "F.Fab")
		)
		(fp_line
			(start 0.67945 -0.3048)
			(end 0.67945 0.3048)
			(stroke
				(width 0.1)
				(type default)
			)
			(layer "F.Fab")
		)
		(fp_line
			(start 0.67945 0.3048)
			(end 0.120396 0.3048)
			(stroke
				(width 0.1)
				(type default)
			)
			(layer "F.Fab")
		)
		(pad "1" smd circle
			(at -0.40005 0)
			(size 0 0)
			(layers "F.Cu" "F.Mask" "F.Paste")
			(net "V_DACR_IO")
		)
		(pad "2" smd circle
			(at 0.40005 0)
			(size 0 0)
			(layers "F.Cu" "F.Mask" "F.Paste")
			(net "GND")
		)
	)
	(footprint ""
		(layer "F.Cu")
		(at 12.319 -86.36)
		(property "Reference" "R454"
			(at 0 0 0)
			(layer "F.SilkS")
			(hide yes)
			(effects
				(font
					(size 1.27 1.27)
				)
			)
		)
		(property "Value" ""
			(at 0 0 0)
			(layer "F.Fab")
			(effects
				(font
					(size 1.27 1.27)
				)
			)
		)
		(duplicate_pad_numbers_are_jumpers no)
		(fp_line
			(start -0.7874 -0.4064)
			(end 0.7874 -0.4064)
			(stroke
				(width 0.1524)
				(type default)
			)
			(layer "F.SilkS")
		)
		(fp_line
			(start -0.7874 0.4064)
			(end -0.7874 -0.4064)
			(stroke
				(width 0.1524)
				(type default)
			)
			(layer "F.SilkS")
		)
		(fp_line
			(start 0.7874 -0.4064)
			(end 0.7874 0.4064)
			(stroke
				(width 0.1524)
				(type default)
			)
			(layer "F.SilkS")
		)
		(fp_line
			(start 0.7874 0.4064)
			(end -0.7874 0.4064)
			(stroke
				(width 0.1524)
				(type default)
			)
			(layer "F.SilkS")
		)
		(fp_line
			(start -0.67945 -0.305054)
			(end -0.12065 -0.305054)
			(stroke
				(width 0.1)
				(type default)
			)
			(layer "F.Fab")
		)
		(fp_line
			(start -0.67945 0.3048)
			(end -0.67945 -0.305054)
			(stroke
				(width 0.1)
				(type default)
			)
			(layer "F.Fab")
		)
		(fp_line
			(start -0.12065 -0.305054)
			(end -0.12065 -0.2794)
			(stroke
				(width 0.1)
				(type default)
			)
			(layer "F.Fab")
		)
		(fp_line
			(start -0.12065 -0.2794)
			(end 0.12065 -0.2794)
			(stroke
				(width 0.1)
				(type default)
			)
			(layer "F.Fab")
		)
		(fp_line
			(start -0.12065 0.2794)
			(end -0.12065 0.3048)
			(stroke
				(width 0.1)
				(type default)
			)
			(layer "F.Fab")
		)
		(fp_line
			(start -0.12065 0.3048)
			(end -0.67945 0.3048)
			(stroke
				(width 0.1)
				(type default)
			)
			(layer "F.Fab")
		)
		(fp_line
			(start 0.120396 0.2794)
			(end -0.12065 0.2794)
			(stroke
				(width 0.1)
				(type default)
			)
			(layer "F.Fab")
		)
		(fp_line
			(start 0.120396 0.3048)
			(end 0.120396 0.2794)
			(stroke
				(width 0.1)
				(type default)
			)
			(layer "F.Fab")
		)
		(fp_line
			(start 0.12065 -0.3048)
			(end 0.67945 -0.3048)
			(stroke
				(width 0.1)
				(type default)
			)
			(layer "F.Fab")
		)
		(fp_line
			(start 0.12065 -0.2794)
			(end 0.12065 -0.3048)
			(stroke
				(width 0.1)
				(type default)
			)
			(layer "F.Fab")
		)
		(fp_line
			(start 0.67945 -0.3048)
			(end 0.67945 0.3048)
			(stroke
				(width 0.1)
				(type default)
			)
			(layer "F.Fab")
		)
		(fp_line
			(start 0.67945 0.3048)
			(end 0.120396 0.3048)
			(stroke
				(width 0.1)
				(type default)
			)
			(layer "F.Fab")
		)
		(pad "1" smd circle
			(at -0.40005 0)
			(size 0 0)
			(layers "F.Cu" "F.Mask" "F.Paste")
			(net "SMB_BMC_ALERT4_N")
		)
		(pad "2" smd circle
			(at 0.40005 0)
			(size 0 0)
			(layers "F.Cu" "F.Mask" "F.Paste")
			(net "SMB_BMC_ALERT4_R1_N")
		)
	)
)
